(kicad_pcb
	(version 20260206)
	(generator "pcbnew")
	(generator_version "10.0")
	(general
		(thickness 1.6)
		(legacy_teardrops no)
	)
	(paper "A4")
	(title_block
		(title "Wiwynn_Tioga_Pass_MB.brd")
		(comment 1 "Tioga Pass / footprint 2008 of 4770 (EU4A3), pads 1-43 of 43")
	)
	(layers
		(0 "F.Cu" signal "TOP")
		(4 "In1.Cu" signal "L2GND")
		(6 "In2.Cu" signal "L3")
		(8 "In3.Cu" signal "L4GND")
		(10 "In4.Cu" signal "L5")
		(12 "In5.Cu" signal "L6GND")
		(14 "In6.Cu" signal "L7VCC")
		(16 "In7.Cu" signal "L8VCC")
		(18 "In8.Cu" signal "L9GND")
		(20 "In9.Cu" signal "L10")
		(22 "In10.Cu" signal "L11GND")
		(24 "In11.Cu" signal "L12")
		(26 "In12.Cu" signal "L13GND")
		(2 "B.Cu" signal "BOTTOM")
		(9 "F.Adhes" user "F.Adhesive")
		(11 "B.Adhes" user "B.Adhesive")
		(13 "F.Paste" user "Package Geometry/Pastemask Top")
		(15 "B.Paste" user "Package Geometry/Pastemask Bottom")
		(5 "F.SilkS" user "Ref Des/Silkscreen Top")
		(7 "B.SilkS" user "Ref Des/Silkscreen Bottom")
		(1 "F.Mask" user "Board Geometry/Soldermask Top")
		(3 "B.Mask" user "Board Geometry/Soldermask Bottom")
		(17 "Dwgs.User" user "User.Drawings")
		(19 "Cmts.User" user "User.Comments")
		(21 "Eco1.User" user "User.Eco1")
		(23 "Eco2.User" user "User.Eco2")
		(25 "Edge.Cuts" user "Board Geometry/Outline")
		(27 "Margin" user)
		(31 "F.CrtYd" user "Package Geometry/Place Bound Top")
		(29 "B.CrtYd" user "Package Geometry/Place Bound Bottom")
		(35 "F.Fab" user "Ref Des/Assembly Top")
		(33 "B.Fab" user "Ref Des/Assembly Bottom")
	)
	(footprint ""
		(layer "F.Cu")
		(at 177.673 -136.8425 90)
		(property "Reference" "EU4A3"
			(at 5.29463 0.1778 0)
			(unlocked yes)
			(layer "F.SilkS")
			(effects
				(font
					(size 0.7874 0.5842)
					(thickness 0.1524)
				)
				(justify left)
			)
		)
		(property "Value" ""
			(at 0 0 90)
			(layer "F.Fab")
			(effects
				(font
					(size 1.27 1.27)
				)
			)
		)
		(duplicate_pad_numbers_are_jumpers no)
		(pad "1" smd custom
			(at -2.8321 -2.249932 90)
			(size 0.06985 0.06985)
			(layers "F.Cu" "F.Mask" "F.Paste")
			(net "VR_PVPP_KLM_SS")
			(options
				(clearance outline)
				(anchor circle)
			)
			(primitives
				(gr_poly
					(pts
						(arc
							(start 0.2413 -0.1397)
							(mid 0.381 0)
							(end 0.2413 0.1397)
						)
						(xy -0.381 0.1397) (xy -0.381 -0.1397)
					)
					(width 0)
					(fill yes)
				)
			)
		)
		(pad "2" smd custom
			(at -2.8321 -1.75006 90)
			(size 0.06985 0.06985)
			(layers "F.Cu" "F.Mask" "F.Paste")
			(net "VR_FB_PVPP_KLM")
			(options
				(clearance outline)
				(anchor circle)
			)
			(primitives
				(gr_poly
					(pts
						(arc
							(start 0.2413 -0.1397)
							(mid 0.381 0)
							(end 0.2413 0.1397)
						)
						(xy -0.381 0.1397) (xy -0.381 -0.1397)
					)
					(width 0)
					(fill yes)
				)
			)
		)
		(pad "3" smd custom
			(at -2.8321 -1.249934 90)
			(size 0.06985 0.06985)
			(layers "F.Cu" "F.Mask" "F.Paste")
			(net "VR_COMP_PVPP_KLM_3")
			(options
				(clearance outline)
				(anchor circle)
			)
			(primitives
				(gr_poly
					(pts
						(arc
							(start 0.2413 -0.1397)
							(mid 0.381 0)
							(end 0.2413 0.1397)
						)
						(xy -0.381 0.1397) (xy -0.381 -0.1397)
					)
					(width 0)
					(fill yes)
				)
			)
		)
		(pad "4" smd custom
			(at -2.8321 -0.750062 90)
			(size 0.06985 0.06985)
			(layers "F.Cu" "F.Mask" "F.Paste")
			(net "VR_PVPP_KLM_ISET")
			(options
				(clearance outline)
				(anchor circle)
			)
			(primitives
				(gr_poly
					(pts
						(arc
							(start 0.2413 -0.1397)
							(mid 0.381 0)
							(end 0.2413 0.1397)
						)
						(xy -0.381 0.1397) (xy -0.381 -0.1397)
					)
					(width 0)
					(fill yes)
				)
			)
		)
		(pad "5" smd custom
			(at -2.8321 -0.249936 90)
			(size 0.06985 0.06985)
			(layers "F.Cu" "F.Mask" "F.Paste")
			(net "AGND_PVPP_KLM")
			(options
				(clearance outline)
				(anchor circle)
			)
			(primitives
				(gr_poly
					(pts
						(arc
							(start 0.2413 -0.1397)
							(mid 0.381 0)
							(end 0.2413 0.1397)
						)
						(xy -0.381 0.1397) (xy -0.381 -0.1397)
					)
					(width 0)
					(fill yes)
				)
			)
		)
		(pad "6" smd custom
			(at -2.8321 0.249936 90)
			(size 0.06985 0.06985)
			(layers "F.Cu" "F.Mask" "F.Paste")
			(net "AGND_PVPP_KLM")
			(options
				(clearance outline)
				(anchor circle)
			)
			(primitives
				(gr_poly
					(pts
						(arc
							(start 0.2413 -0.1397)
							(mid 0.381 0)
							(end 0.2413 0.1397)
						)
						(xy -0.381 0.1397) (xy -0.381 -0.1397)
					)
					(width 0)
					(fill yes)
				)
			)
		)
		(pad "7" smd custom
			(at -2.8321 0.750062 90)
			(size 0.06985 0.06985)
			(layers "F.Cu" "F.Mask" "F.Paste")
			(net "PWRGD_PVPP_KLM_R")
			(options
				(clearance outline)
				(anchor circle)
			)
			(primitives
				(gr_poly
					(pts
						(arc
							(start 0.2413 -0.1397)
							(mid 0.381 0)
							(end 0.2413 0.1397)
						)
						(xy -0.381 0.1397) (xy -0.381 -0.1397)
					)
					(width 0)
					(fill yes)
				)
			)
		)
		(pad "8" smd custom
			(at -2.8321 1.249934 90)
			(size 0.06985 0.06985)
			(layers "F.Cu" "F.Mask" "F.Paste")
			(net "VR_FET_SW_P12V_STBY_PVPP_KLM")
			(options
				(clearance outline)
				(anchor circle)
			)
			(primitives
				(gr_poly
					(pts
						(arc
							(start 0.2413 -0.1397)
							(mid 0.381 0)
							(end 0.2413 0.1397)
						)
						(xy -0.381 0.1397) (xy -0.381 -0.1397)
					)
					(width 0)
					(fill yes)
				)
			)
		)
		(pad "9" smd custom
			(at -2.8321 1.75006 90)
			(size 0.06985 0.06985)
			(layers "F.Cu" "F.Mask" "F.Paste")
			(net "VR_FET_SW_P12V_STBY_PVPP_KLM")
			(options
				(clearance outline)
				(anchor circle)
			)
			(primitives
				(gr_poly
					(pts
						(arc
							(start 0.2413 -0.1397)
							(mid 0.381 0)
							(end 0.2413 0.1397)
						)
						(xy -0.381 0.1397) (xy -0.381 -0.1397)
					)
					(width 0)
					(fill yes)
				)
			)
		)
		(pad "10" smd custom
			(at -2.8321 2.249932 90)
			(size 0.06985 0.06985)
			(layers "F.Cu" "F.Mask" "F.Paste")
			(net "VR_FET_SW_P12V_STBY_PVPP_KLM")
			(options
				(clearance outline)
				(anchor circle)
			)
			(primitives
				(gr_poly
					(pts
						(arc
							(start 0.2413 -0.1397)
							(mid 0.381 0)
							(end 0.2413 0.1397)
						)
						(xy -0.381 0.1397) (xy -0.381 -0.1397)
					)
					(width 0)
					(fill yes)
				)
			)
		)
		(pad "11" smd custom
			(at -2.249932 2.8321 90)
			(size 0.06985 0.06985)
			(layers "F.Cu" "F.Mask" "F.Paste")
			(net "VR_FET_SW_P12V_STBY_PVPP_KLM")
			(options
				(clearance outline)
				(anchor circle)
			)
			(primitives
				(gr_poly
					(pts
						(arc
							(start -0.1397 -0.2413)
							(mid 0 -0.381)
							(end 0.1397 -0.2413)
						)
						(xy 0.1397 0.381) (xy -0.1397 0.381)
					)
					(width 0)
					(fill yes)
				)
			)
		)
		(pad "12" smd custom
			(at -1.75006 2.8321 90)
			(size 0.06985 0.06985)
			(layers "F.Cu" "F.Mask" "F.Paste")
			(net "VR_FET_SW_P12V_STBY_PVPP_KLM")
			(options
				(clearance outline)
				(anchor circle)
			)
			(primitives
				(gr_poly
					(pts
						(arc
							(start -0.1397 -0.2413)
							(mid 0 -0.381)
							(end 0.1397 -0.2413)
						)
						(xy 0.1397 0.381) (xy -0.1397 0.381)
					)
					(width 0)
					(fill yes)
				)
			)
		)
		(pad "13" smd custom
			(at -1.249934 2.8321 90)
			(size 0.06985 0.06985)
			(layers "F.Cu" "F.Mask" "F.Paste")
			(net "VR_FET_SW_P12V_STBY_PVPP_KLM")
			(options
				(clearance outline)
				(anchor circle)
			)
			(primitives
				(gr_poly
					(pts
						(arc
							(start -0.1397 -0.2413)
							(mid 0 -0.381)
							(end 0.1397 -0.2413)
						)
						(xy 0.1397 0.381) (xy -0.1397 0.381)
					)
					(width 0)
					(fill yes)
				)
			)
		)
		(pad "14" smd custom
			(at -0.750062 2.8321 90)
			(size 0.06985 0.06985)
			(layers "F.Cu" "F.Mask" "F.Paste")
			(net "VR_FET_SW_P12V_STBY_PVPP_KLM")
			(options
				(clearance outline)
				(anchor circle)
			)
			(primitives
				(gr_poly
					(pts
						(arc
							(start -0.1397 -0.2413)
							(mid 0 -0.381)
							(end 0.1397 -0.2413)
						)
						(xy 0.1397 0.381) (xy -0.1397 0.381)
					)
					(width 0)
					(fill yes)
				)
			)
		)
		(pad "15" smd custom
			(at -0.249936 2.8321 90)
			(size 0.06985 0.06985)
			(layers "F.Cu" "F.Mask" "F.Paste")
			(net "VR_PVPP_KLM_PHASE")
			(options
				(clearance outline)
				(anchor circle)
			)
			(primitives
				(gr_poly
					(pts
						(arc
							(start -0.1397 -0.2413)
							(mid 0 -0.381)
							(end 0.1397 -0.2413)
						)
						(xy 0.1397 0.381) (xy -0.1397 0.381)
					)
					(width 0)
					(fill yes)
				)
			)
		)
		(pad "16" smd custom
			(at 0.249936 2.8321 90)
			(size 0.06985 0.06985)
			(layers "F.Cu" "F.Mask" "F.Paste")
			(net "GND")
			(options
				(clearance outline)
				(anchor circle)
			)
			(primitives
				(gr_poly
					(pts
						(arc
							(start -0.1397 -0.2413)
							(mid 0 -0.381)
							(end 0.1397 -0.2413)
						)
						(xy 0.1397 0.381) (xy -0.1397 0.381)
					)
					(width 0)
					(fill yes)
				)
			)
		)
		(pad "17" smd custom
			(at 0.750062 2.8321 90)
			(size 0.06985 0.06985)
			(layers "F.Cu" "F.Mask" "F.Paste")
			(net "GND")
			(options
				(clearance outline)
				(anchor circle)
			)
			(primitives
				(gr_poly
					(pts
						(arc
							(start -0.1397 -0.2413)
							(mid 0 -0.381)
							(end 0.1397 -0.2413)
						)
						(xy 0.1397 0.381) (xy -0.1397 0.381)
					)
					(width 0)
					(fill yes)
				)
			)
		)
		(pad "18" smd custom
			(at 1.249934 2.8321 90)
			(size 0.06985 0.06985)
			(layers "F.Cu" "F.Mask" "F.Paste")
			(net "GND")
			(options
				(clearance outline)
				(anchor circle)
			)
			(primitives
				(gr_poly
					(pts
						(arc
							(start -0.1397 -0.2413)
							(mid 0 -0.381)
							(end 0.1397 -0.2413)
						)
						(xy 0.1397 0.381) (xy -0.1397 0.381)
					)
					(width 0)
					(fill yes)
				)
			)
		)
		(pad "19" smd custom
			(at 1.75006 2.8321 90)
			(size 0.06985 0.06985)
			(layers "F.Cu" "F.Mask" "F.Paste")
			(net "GND")
			(options
				(clearance outline)
				(anchor circle)
			)
			(primitives
				(gr_poly
					(pts
						(arc
							(start -0.1397 -0.2413)
							(mid 0 -0.381)
							(end 0.1397 -0.2413)
						)
						(xy 0.1397 0.381) (xy -0.1397 0.381)
					)
					(width 0)
					(fill yes)
				)
			)
		)
		(pad "20" smd custom
			(at 2.249932 2.8321 90)
			(size 0.06985 0.06985)
			(layers "F.Cu" "F.Mask" "F.Paste")
			(net "GND")
			(options
				(clearance outline)
				(anchor circle)
			)
			(primitives
				(gr_poly
					(pts
						(arc
							(start -0.1397 -0.2413)
							(mid 0 -0.381)
							(end 0.1397 -0.2413)
						)
						(xy 0.1397 0.381) (xy -0.1397 0.381)
					)
					(width 0)
					(fill yes)
				)
			)
		)
		(pad "21" smd custom
			(at 2.8321 2.249932 90)
			(size 0.06985 0.06985)
			(layers "F.Cu" "F.Mask" "F.Paste")
			(net "GND")
			(options
				(clearance outline)
				(anchor circle)
			)
			(primitives
				(gr_poly
					(pts
						(arc
							(start -0.2413 0.1397)
							(mid -0.381 0)
							(end -0.2413 -0.1397)
						)
						(xy 0.381 -0.1397) (xy 0.381 0.1397)
					)
					(width 0)
					(fill yes)
				)
			)
		)
		(pad "22" smd custom
			(at 2.8321 1.75006 90)
			(size 0.06985 0.06985)
			(layers "F.Cu" "F.Mask" "F.Paste")
			(net "GND")
			(options
				(clearance outline)
				(anchor circle)
			)
			(primitives
				(gr_poly
					(pts
						(arc
							(start -0.2413 0.1397)
							(mid -0.381 0)
							(end -0.2413 -0.1397)
						)
						(xy 0.381 -0.1397) (xy 0.381 0.1397)
					)
					(width 0)
					(fill yes)
				)
			)
		)
		(pad "23" smd custom
			(at 2.8321 1.249934 90)
			(size 0.06985 0.06985)
			(layers "F.Cu" "F.Mask" "F.Paste")
			(net "GND")
			(options
				(clearance outline)
				(anchor circle)
			)
			(primitives
				(gr_poly
					(pts
						(arc
							(start -0.2413 0.1397)
							(mid -0.381 0)
							(end -0.2413 -0.1397)
						)
						(xy 0.381 -0.1397) (xy 0.381 0.1397)
					)
					(width 0)
					(fill yes)
				)
			)
		)
		(pad "24" smd custom
			(at 2.8321 0.750062 90)
			(size 0.06985 0.06985)
			(layers "F.Cu" "F.Mask" "F.Paste")
			(net "GND")
			(options
				(clearance outline)
				(anchor circle)
			)
			(primitives
				(gr_poly
					(pts
						(arc
							(start -0.2413 0.1397)
							(mid -0.381 0)
							(end -0.2413 -0.1397)
						)
						(xy 0.381 -0.1397) (xy 0.381 0.1397)
					)
					(width 0)
					(fill yes)
				)
			)
		)
		(pad "25" smd custom
			(at 2.8321 0.249936 90)
			(size 0.06985 0.06985)
			(layers "F.Cu" "F.Mask" "F.Paste")
			(net "GND")
			(options
				(clearance outline)
				(anchor circle)
			)
			(primitives
				(gr_poly
					(pts
						(arc
							(start -0.2413 0.1397)
							(mid -0.381 0)
							(end -0.2413 -0.1397)
						)
						(xy 0.381 -0.1397) (xy 0.381 0.1397)
					)
					(width 0)
					(fill yes)
				)
			)
		)
		(pad "26" smd custom
			(at 2.8321 -0.249936 90)
			(size 0.06985 0.06985)
			(layers "F.Cu" "F.Mask" "F.Paste")
			(net "GND")
			(options
				(clearance outline)
				(anchor circle)
			)
			(primitives
				(gr_poly
					(pts
						(arc
							(start -0.2413 0.1397)
							(mid -0.381 0)
							(end -0.2413 -0.1397)
						)
						(xy 0.381 -0.1397) (xy 0.381 0.1397)
					)
					(width 0)
					(fill yes)
				)
			)
		)
		(pad "27" smd custom
			(at 2.8321 -0.750062 90)
			(size 0.06985 0.06985)
			(layers "F.Cu" "F.Mask" "F.Paste")
			(net "GND")
			(options
				(clearance outline)
				(anchor circle)
			)
			(primitives
				(gr_poly
					(pts
						(arc
							(start -0.2413 0.1397)
							(mid -0.381 0)
							(end -0.2413 -0.1397)
						)
						(xy 0.381 -0.1397) (xy 0.381 0.1397)
					)
					(width 0)
					(fill yes)
				)
			)
		)
		(pad "28" smd custom
			(at 2.8321 -1.249934 90)
			(size 0.06985 0.06985)
			(layers "F.Cu" "F.Mask" "F.Paste")
			(net "GND")
			(options
				(clearance outline)
				(anchor circle)
			)
			(primitives
				(gr_poly
					(pts
						(arc
							(start -0.2413 0.1397)
							(mid -0.381 0)
							(end -0.2413 -0.1397)
						)
						(xy 0.381 -0.1397) (xy 0.381 0.1397)
					)
					(width 0)
					(fill yes)
				)
			)
		)
		(pad "29" smd custom
			(at 2.8321 -1.75006 90)
			(size 0.06985 0.06985)
			(layers "F.Cu" "F.Mask" "F.Paste")
			(net "VR_PVPP_KLM_PHASE")
			(options
				(clearance outline)
				(anchor circle)
			)
			(primitives
				(gr_poly
					(pts
						(arc
							(start -0.2413 0.1397)
							(mid -0.381 0)
							(end -0.2413 -0.1397)
						)
						(xy 0.381 -0.1397) (xy 0.381 0.1397)
					)
					(width 0)
					(fill yes)
				)
			)
		)
		(pad "30" smd custom
			(at 2.8321 -2.249932 90)
			(size 0.06985 0.06985)
			(layers "F.Cu" "F.Mask" "F.Paste")
			(net "VR_PVPP_KLM_PHASE")
			(options
				(clearance outline)
				(anchor circle)
			)
			(primitives
				(gr_poly
					(pts
						(arc
							(start -0.2413 0.1397)
							(mid -0.381 0)
							(end -0.2413 -0.1397)
						)
						(xy 0.381 -0.1397) (xy 0.381 0.1397)
					)
					(width 0)
					(fill yes)
				)
			)
		)
		(pad "31" smd custom
			(at 2.249932 -2.8321 90)
			(size 0.06985 0.06985)
			(layers "F.Cu" "F.Mask" "F.Paste")
			(net "VR_PVPP_KLM_PHASE")
			(options
				(clearance outline)
				(anchor circle)
			)
			(primitives
				(gr_poly
					(pts
						(arc
							(start 0.1397 0.2413)
							(mid 0 0.381)
							(end -0.1397 0.2413)
						)
						(xy -0.1397 -0.381) (xy 0.1397 -0.381)
					)
					(width 0)
					(fill yes)
				)
			)
		)
		(pad "32" smd custom
			(at 1.75006 -2.8321 90)
			(size 0.06985 0.06985)
			(layers "F.Cu" "F.Mask" "F.Paste")
			(net "VR_PVPP_KLM_PHASE")
			(options
				(clearance outline)
				(anchor circle)
			)
			(primitives
				(gr_poly
					(pts
						(arc
							(start 0.1397 0.2413)
							(mid 0 0.381)
							(end -0.1397 0.2413)
						)
						(xy -0.1397 -0.381) (xy 0.1397 -0.381)
					)
					(width 0)
					(fill yes)
				)
			)
		)
		(pad "33" smd custom
			(at 1.249934 -2.8321 90)
			(size 0.06985 0.06985)
			(layers "F.Cu" "F.Mask" "F.Paste")
			(net "VR_PVPP_KLM_PHASE")
			(options
				(clearance outline)
				(anchor circle)
			)
			(primitives
				(gr_poly
					(pts
						(arc
							(start 0.1397 0.2413)
							(mid 0 0.381)
							(end -0.1397 0.2413)
						)
						(xy -0.1397 -0.381) (xy 0.1397 -0.381)
					)
					(width 0)
					(fill yes)
				)
			)
		)
		(pad "34" smd custom
			(at 0.750062 -2.8321 90)
			(size 0.06985 0.06985)
			(layers "F.Cu" "F.Mask" "F.Paste")
			(net "VR_PVPP_KLM_PHASE")
			(options
				(clearance outline)
				(anchor circle)
			)
			(primitives
				(gr_poly
					(pts
						(arc
							(start 0.1397 0.2413)
							(mid 0 0.381)
							(end -0.1397 0.2413)
						)
						(xy -0.1397 -0.381) (xy 0.1397 -0.381)
					)
					(width 0)
					(fill yes)
				)
			)
		)
		(pad "35" smd custom
			(at 0.249936 -2.8321 90)
			(size 0.06985 0.06985)
			(layers "F.Cu" "F.Mask" "F.Paste")
			(net "VR_PVPP_KLM_PHASE")
			(options
				(clearance outline)
				(anchor circle)
			)
			(primitives
				(gr_poly
					(pts
						(arc
							(start 0.1397 0.2413)
							(mid 0 0.381)
							(end -0.1397 0.2413)
						)
						(xy -0.1397 -0.381) (xy 0.1397 -0.381)
					)
					(width 0)
					(fill yes)
				)
			)
		)
		(pad "36" smd custom
			(at -0.249936 -2.8321 90)
			(size 0.06985 0.06985)
			(layers "F.Cu" "F.Mask" "F.Paste")
			(net "VR_PVPP_KLM_BOOT")
			(options
				(clearance outline)
				(anchor circle)
			)
			(primitives
				(gr_poly
					(pts
						(arc
							(start 0.1397 0.2413)
							(mid 0 0.381)
							(end -0.1397 0.2413)
						)
						(xy -0.1397 -0.381) (xy 0.1397 -0.381)
					)
					(width 0)
					(fill yes)
				)
			)
		)
		(pad "37" smd custom
			(at -0.750062 -2.8321 90)
			(size 0.06985 0.06985)
			(layers "F.Cu" "F.Mask" "F.Paste")
			(net "GND")
			(options
				(clearance outline)
				(anchor circle)
			)
			(primitives
				(gr_poly
					(pts
						(arc
							(start 0.1397 0.2413)
							(mid 0 0.381)
							(end -0.1397 0.2413)
						)
						(xy -0.1397 -0.381) (xy 0.1397 -0.381)
					)
					(width 0)
					(fill yes)
				)
			)
		)
		(pad "38" smd custom
			(at -1.249934 -2.8321 90)
			(size 0.06985 0.06985)
			(layers "F.Cu" "F.Mask" "F.Paste")
			(net "VR_VB_PVPP_KLM")
			(options
				(clearance outline)
				(anchor circle)
			)
			(primitives
				(gr_poly
					(pts
						(arc
							(start 0.1397 0.2413)
							(mid 0 0.381)
							(end -0.1397 0.2413)
						)
						(xy -0.1397 -0.381) (xy 0.1397 -0.381)
					)
					(width 0)
					(fill yes)
				)
			)
		)
		(pad "39" smd custom
			(at -1.75006 -2.8321 90)
			(size 0.06985 0.06985)
			(layers "F.Cu" "F.Mask" "F.Paste")
			(net "VR_FET_SW_P12V_STBY_PVPP_KLM")
			(options
				(clearance outline)
				(anchor circle)
			)
			(primitives
				(gr_poly
					(pts
						(arc
							(start 0.1397 0.2413)
							(mid 0 0.381)
							(end -0.1397 0.2413)
						)
						(xy -0.1397 -0.381) (xy 0.1397 -0.381)
					)
					(width 0)
					(fill yes)
				)
			)
		)
		(pad "40" smd custom
			(at -2.249932 -2.8321 90)
			(size 0.06985 0.06985)
			(layers "F.Cu" "F.Mask" "F.Paste")
			(net "FM_PVPP_PVDDQ_CPU1_EN_KLM")
			(options
				(clearance outline)
				(anchor circle)
			)
			(primitives
				(gr_poly
					(pts
						(arc
							(start 0.1397 0.2413)
							(mid 0 0.381)
							(end -0.1397 0.2413)
						)
						(xy -0.1397 -0.381) (xy 0.1397 -0.381)
					)
					(width 0)
					(fill yes)
				)
			)
		)
		(pad "41" smd rect
			(at -1.4478 -1.1938 90)
			(size 1.4986 2.0066)
			(layers "F.Cu" "F.Mask" "F.Paste")
			(net "GND")
		)
		(pad "42" smd rect
			(at -1.4478 1.1938 90)
			(size 1.4986 2.0066)
			(layers "F.Cu" "F.Mask" "F.Paste")
			(net "VR_FET_SW_P12V_STBY_PVPP_KLM")
		)
		(pad "43" smd rect
			(at 1.0033 0 90)
			(size 2.3876 4.3942)
			(layers "F.Cu" "F.Mask" "F.Paste")
			(net "VR_PVPP_KLM_PHASE")
		)
	)
)
